(kicad_pcb
	(version 20260206)
	(generator "pcbnew")
	(generator_version "10.0")
	(general
		(thickness 1.6)
		(legacy_teardrops no)
	)
	(paper "A4")
	(title_block
		(title "v1-chassis-manager — T6M_CM_d_v01_1031_1645.brd")
		(comment 1 "Open CloudServer (Microsoft) / footprints 1399-1407 of 2512")
	)
	(layers
		(0 "F.Cu" signal "TOP")
		(4 "In1.Cu" signal "GND1")
		(6 "In2.Cu" signal "IN1")
		(8 "In3.Cu" signal "VCC1")
		(10 "In4.Cu" signal "VCC2")
		(12 "In5.Cu" signal "GND2")
		(14 "In6.Cu" signal "IN2")
		(16 "In7.Cu" signal "IN3")
		(18 "In8.Cu" signal "GND3")
		(2 "B.Cu" signal "BOTTOM")
		(9 "F.Adhes" user "F.Adhesive")
		(11 "B.Adhes" user "B.Adhesive")
		(13 "F.Paste" user "Package Geometry/Pastemask Top")
		(15 "B.Paste" user "Package Geometry/Pastemask Bottom")
		(5 "F.SilkS" user "Ref Des/Silkscreen Top")
		(7 "B.SilkS" user "Ref Des/Silkscreen Bottom")
		(1 "F.Mask" user "Board Geometry/Soldermask Top")
		(3 "B.Mask" user "Board Geometry/Soldermask Bottom")
		(17 "Dwgs.User" user "User.Drawings")
		(19 "Cmts.User" user "User.Comments")
		(21 "Eco1.User" user "User.Eco1")
		(23 "Eco2.User" user "User.Eco2")
		(25 "Edge.Cuts" user "Board Geometry/Outline")
		(27 "Margin" user)
		(31 "F.CrtYd" user "Package Geometry/Place Bound Top")
		(29 "B.CrtYd" user "Package Geometry/Place Bound Bottom")
		(35 "F.Fab" user "Ref Des/Assembly Top")
		(33 "B.Fab" user "Ref Des/Assembly Bottom")
	)
	(footprint ""
		(layer "F.Cu")
		(at 33.344104 -118.551452)
		(property "Reference" "R1116"
			(at -6.116828 0.981456 0)
			(unlocked yes)
			(layer "F.SilkS")
			(effects
				(font
					(size 0.7874 0.5842)
					(thickness 0.1524)
				)
				(justify left)
			)
		)
		(property "Value" ""
			(at 0 0 0)
			(layer "F.Fab")
			(effects
				(font
					(size 1.27 1.27)
				)
			)
		)
		(duplicate_pad_numbers_are_jumpers no)
		(fp_line
			(start -0.7874 -0.4064)
			(end 0.7874 -0.4064)
			(stroke
				(width 0.1524)
				(type default)
			)
			(layer "F.SilkS")
		)
		(fp_line
			(start -0.7874 0.4064)
			(end -0.7874 -0.4064)
			(stroke
				(width 0.1524)
				(type default)
			)
			(layer "F.SilkS")
		)
		(fp_line
			(start 0.7874 -0.4064)
			(end 0.7874 0.4064)
			(stroke
				(width 0.1524)
				(type default)
			)
			(layer "F.SilkS")
		)
		(fp_line
			(start 0.7874 0.4064)
			(end -0.7874 0.4064)
			(stroke
				(width 0.1524)
				(type default)
			)
			(layer "F.SilkS")
		)
		(fp_poly
			(pts
				(xy -0.508 0.2794) (xy -0.508 0.2286) (xy -0.635 0.2286) (xy -0.635 -0.254) (xy -0.5334 -0.254)
				(xy -0.5334 -0.2794) (xy 0.5334 -0.2794) (xy 0.5334 -0.254) (xy 0.635 -0.254) (xy 0.635 0.254) (xy 0.5334 0.254)
				(xy 0.5334 0.2794)
			)
			(stroke
				(width 0)
				(type default)
			)
			(fill no)
			(layer "F.CrtYd")
		)
		(pad "1" smd rect
			(at 0.40005 0)
			(size 0.4572 0.508)
			(layers "F.Cu" "F.Mask" "F.Paste")
			(net "FM_CPLD_NODE1_P1V5_EN")
		)
		(pad "2" smd rect
			(at -0.40005 0)
			(size 0.4572 0.508)
			(layers "F.Cu" "F.Mask" "F.Paste")
			(net "P3V3_STB_NODE1")
		)
	)
	(footprint ""
		(layer "F.Cu")
		(at 60.469526 -161.888932 -90)
		(property "Reference" "Q36"
			(at 0.21463 -10.954258 90)
			(unlocked yes)
			(layer "F.SilkS")
			(effects
				(font
					(size 0.7874 0.5842)
					(thickness 0.1524)
				)
			)
		)
		(property "Value" ""
			(at 0 0 270)
			(layer "F.Fab")
			(effects
				(font
					(size 1.27 1.27)
				)
			)
		)
		(duplicate_pad_numbers_are_jumpers no)
		(fp_line
			(start -1.603248 1.500124)
			(end -1.603248 -1.500124)
			(stroke
				(width 0.1524)
				(type default)
			)
			(layer "F.SilkS")
		)
		(fp_line
			(start 1.603248 1.500124)
			(end -1.603248 1.500124)
			(stroke
				(width 0.1524)
				(type default)
			)
			(layer "F.SilkS")
		)
		(fp_line
			(start -1.603248 -1.500124)
			(end 1.603248 -1.500124)
			(stroke
				(width 0.1524)
				(type default)
			)
			(layer "F.SilkS")
		)
		(fp_line
			(start 1.603248 -1.500124)
			(end 1.603248 1.500124)
			(stroke
				(width 0.1524)
				(type default)
			)
			(layer "F.SilkS")
		)
		(fp_poly
			(pts
				(xy -0.700024 -1.500124) (xy -0.700024 -1.40716) (xy -1.507998 -1.40716) (xy -1.507998 -0.49276)
				(xy -0.700024 -0.49276) (xy -0.700024 0.47244) (xy -1.507998 0.47244) (xy -1.507998 1.41224) (xy -0.700024 1.41224)
				(xy -0.700024 1.500124) (xy 0.700024 1.500124) (xy 0.700024 0.47244) (xy 1.514602 0.47244) (xy 1.514602 -0.46736)
				(xy 0.700024 -0.46736) (xy 0.700024 -1.500124)
			)
			(stroke
				(width 0)
				(type default)
			)
			(fill no)
			(layer "F.CrtYd")
		)
		(fp_line
			(start -0.700024 1.500124)
			(end -0.700024 -1.500124)
			(stroke
				(width 0.1)
				(type default)
			)
			(layer "F.Fab")
		)
		(fp_line
			(start 0.700024 1.500124)
			(end -0.700024 1.500124)
			(stroke
				(width 0.1)
				(type default)
			)
			(layer "F.Fab")
		)
		(fp_line
			(start -0.700024 -1.500124)
			(end 0.700024 -1.500124)
			(stroke
				(width 0.1)
				(type default)
			)
			(layer "F.Fab")
		)
		(fp_line
			(start 0.700024 -1.500124)
			(end 0.700024 1.500124)
			(stroke
				(width 0.1)
				(type default)
			)
			(layer "F.Fab")
		)
		(fp_text user "S"
			(at 1.451864 1.890268 0)
			(unlocked yes)
			(layer "F.SilkS")
			(effects
				(font
					(size 0.635 0.4064)
					(thickness 0.1524)
				)
			)
		)
		(fp_text user "D"
			(at 2.252218 -0.858774 0)
			(unlocked yes)
			(layer "F.SilkS")
			(effects
				(font
					(size 0.635 0.4064)
					(thickness 0.1524)
				)
			)
		)
		(fp_text user "G"
			(at -0.907796 -2.31775 0)
			(unlocked yes)
			(layer "F.SilkS")
			(effects
				(font
					(size 0.635 0.4064)
					(thickness 0.1524)
				)
			)
		)
		(fp_text user "S"
			(at -1.025906 2.0066 180)
			(unlocked yes)
			(layer "F.Fab")
			(effects
				(font
					(size 0.7874 0.5842)
					(thickness 0.000001)
				)
			)
		)
		(fp_text user "D"
			(at 2.098294 0.1016 180)
			(unlocked yes)
			(layer "F.Fab")
			(effects
				(font
					(size 0.7874 0.5842)
					(thickness 0.000001)
				)
			)
		)
		(fp_text user "G"
			(at -1.051306 -2.032 180)
			(unlocked yes)
			(layer "F.Fab")
			(effects
				(font
					(size 0.7874 0.5842)
					(thickness 0.000001)
				)
			)
		)
		(pad "D" smd rect
			(at 0.999998 0 180)
			(size 0.8128 0.9144)
			(layers "F.Cu" "F.Mask" "F.Paste")
			(net "FM_CPLD_NODE1_P5V_EN_LV")
		)
		(pad "G" smd rect
			(at -0.999998 -0.94996 180)
			(size 0.8128 0.9144)
			(layers "F.Cu" "F.Mask" "F.Paste")
			(net "FM_CPLD_NODE1_P5V_NODE1_EN_G")
		)
		(pad "S" smd rect
			(at -0.999998 0.94996 180)
			(size 0.8128 0.9144)
			(layers "F.Cu" "F.Mask" "F.Paste")
			(net "FM_CPLD_NODE1_P5V_EN")
		)
	)
	(footprint ""
		(layer "F.Cu")
		(at 109.30001 -156.330142 180)
		(property "Reference" "U108"
			(at -4.302252 3.040126 90)
			(unlocked yes)
			(layer "F.SilkS")
			(effects
				(font
					(size 0.635 0.4064)
					(thickness 0.1524)
				)
			)
		)
		(property "Value" ""
			(at 0 0 180)
			(layer "F.Fab")
			(effects
				(font
					(size 1.27 1.27)
				)
			)
		)
		(duplicate_pad_numbers_are_jumpers no)
		(fp_line
			(start 1.651 1.905)
			(end -1.651 1.905)
			(stroke
				(width 0.1524)
				(type default)
			)
			(layer "F.SilkS")
		)
		(fp_line
			(start 1.651 -1.905)
			(end 1.651 1.905)
			(stroke
				(width 0.1524)
				(type default)
			)
			(layer "F.SilkS")
		)
		(fp_line
			(start -1.651 1.905)
			(end -1.651 -1.905)
			(stroke
				(width 0.1524)
				(type default)
			)
			(layer "F.SilkS")
		)
		(fp_line
			(start -1.651 -1.905)
			(end 1.651 -1.905)
			(stroke
				(width 0.1524)
				(type default)
			)
			(layer "F.SilkS")
		)
		(fp_poly
			(pts
				(xy -1.524 0.7112) (xy -1.524 1.7526) (xy -0.508 1.7526) (xy -0.508 0.6985) (xy 0.508 0.6985) (xy 0.508 1.7526)
				(xy 1.524 1.7526) (xy 1.524 0.6985) (xy 1.524 -0.6985) (xy 0.508 -0.6985) (xy 0.508 -1.7526) (xy -0.508 -1.7526)
				(xy -0.508 -0.6985) (xy -1.524 -0.6985) (xy -1.524 0.6985)
			)
			(stroke
				(width 0)
				(type default)
			)
			(fill no)
			(layer "F.CrtYd")
		)
		(fp_text user "D"
			(at 0.947928 -1.425448 0)
			(unlocked yes)
			(layer "F.SilkS")
			(effects
				(font
					(size 0.635 0.4064)
					(thickness 0.1524)
				)
			)
		)
		(fp_text user "G"
			(at 0.09779 1.149604 0)
			(unlocked yes)
			(layer "F.SilkS")
			(effects
				(font
					(size 0.635 0.4064)
					(thickness 0.1524)
				)
			)
		)
		(fp_text user "S"
			(at -1.046988 -1.28397 0)
			(unlocked yes)
			(layer "F.SilkS")
			(effects
				(font
					(size 0.635 0.4064)
					(thickness 0.1524)
				)
			)
		)
		(pad "D" smd rect
			(at 0 -1.1176 180)
			(size 1.016 1.27)
			(layers "F.Cu" "F.Mask" "F.Paste")
			(net "N52411212")
		)
		(pad "G" smd rect
			(at -1.016 1.1176 180)
			(size 1.016 1.27)
			(layers "F.Cu" "F.Mask" "F.Paste")
			(net "N52410978")
		)
		(pad "S" smd rect
			(at 1.016 1.1176 180)
			(size 1.016 1.27)
			(layers "F.Cu" "F.Mask" "F.Paste")
			(net "GND")
		)
	)
	(footprint ""
		(layer "F.Cu")
		(at 88.232488 -157.737302)
		(property "Reference" "PC130"
			(at -1.467104 6.650482 0)
			(unlocked yes)
			(layer "F.SilkS")
			(effects
				(font
					(size 0.7874 0.5842)
					(thickness 0.1524)
				)
				(justify left)
			)
		)
		(property "Value" ""
			(at 0 0 0)
			(layer "F.Fab")
			(effects
				(font
					(size 1.27 1.27)
				)
			)
		)
		(duplicate_pad_numbers_are_jumpers no)
		(fp_line
			(start -1.905 -0.8636)
			(end 1.905 -0.8636)
			(stroke
				(width 0.1524)
				(type default)
			)
			(layer "F.SilkS")
		)
		(fp_line
			(start -1.905 0.8636)
			(end -1.905 -0.8636)
			(stroke
				(width 0.1524)
				(type default)
			)
			(layer "F.SilkS")
		)
		(fp_line
			(start 0 0.8382)
			(end 0 -0.8382)
			(stroke
				(width 0.1524)
				(type default)
			)
			(layer "F.SilkS")
		)
		(fp_line
			(start 1.905 -0.8636)
			(end 1.905 0.8636)
			(stroke
				(width 0.1524)
				(type default)
			)
			(layer "F.SilkS")
		)
		(fp_line
			(start 1.905 0.8636)
			(end -1.905 0.8636)
			(stroke
				(width 0.1524)
				(type default)
			)
			(layer "F.SilkS")
		)
		(fp_rect
			(start -1.524 0.7366)
			(end 1.524 -0.7366)
			(stroke
				(width 0)
				(type default)
			)
			(fill no)
			(layer "F.CrtYd")
		)
		(pad "1" smd rect
			(at 0.94996 0)
			(size 1.1176 1.3716)
			(layers "F.Cu" "F.Mask" "F.Paste")
			(net "P1V8_STB_NODE1")
		)
		(pad "2" smd rect
			(at -0.94996 0)
			(size 1.1176 1.3716)
			(layers "F.Cu" "F.Mask" "F.Paste")
			(net "GND")
		)
	)
	(footprint ""
		(layer "F.Cu")
		(at 84.18322 -8.212074 180)
		(property "Reference" "PC50"
			(at -2.287524 -4.117848 0)
			(unlocked yes)
			(layer "F.SilkS")
			(effects
				(font
					(size 0.7874 0.5842)
					(thickness 0.1524)
				)
				(justify left)
			)
		)
		(property "Value" ""
			(at 0 0 180)
			(layer "F.Fab")
			(effects
				(font
					(size 1.27 1.27)
				)
			)
		)
		(duplicate_pad_numbers_are_jumpers no)
		(fp_line
			(start 0.7874 0.4064)
			(end -0.7874 0.4064)
			(stroke
				(width 0.1524)
				(type default)
			)
			(layer "F.SilkS")
		)
		(fp_line
			(start 0.7874 -0.4064)
			(end 0.7874 0.4064)
			(stroke
				(width 0.1524)
				(type default)
			)
			(layer "F.SilkS")
		)
		(fp_line
			(start 0 0.381)
			(end 0 -0.381)
			(stroke
				(width 0.1524)
				(type default)
			)
			(layer "F.SilkS")
		)
		(fp_line
			(start -0.7874 0.4064)
			(end -0.7874 -0.4064)
			(stroke
				(width 0.1524)
				(type default)
			)
			(layer "F.SilkS")
		)
		(fp_line
			(start -0.7874 -0.4064)
			(end 0.7874 -0.4064)
			(stroke
				(width 0.1524)
				(type default)
			)
			(layer "F.SilkS")
		)
		(fp_poly
			(pts
				(xy -0.5334 0.254) (xy -0.635 0.254) (xy -0.635 0.2286) (xy -0.635 -0.254) (xy -0.5334 -0.254) (xy -0.5334 -0.2794)
				(xy 0.5334 -0.2794) (xy 0.5334 -0.254) (xy 0.635 -0.254) (xy 0.635 0.254) (xy 0.5334 0.254) (xy 0.5334 0.2794)
				(xy -0.508 0.2794) (xy -0.5334 0.2794)
			)
			(stroke
				(width 0)
				(type default)
			)
			(fill no)
			(layer "F.CrtYd")
		)
		(pad "1" smd rect
			(at 0.40005 0 180)
			(size 0.4572 0.508)
			(layers "F.Cu" "F.Mask" "F.Paste")
			(net "P3V3_NODE1")
		)
		(pad "2" smd rect
			(at -0.40005 0 180)
			(size 0.4572 0.508)
			(layers "F.Cu" "F.Mask" "F.Paste")
			(net "GND")
		)
	)
	(footprint ""
		(layer "F.Cu")
		(at 184.3786 -182.8292)
		(property "Reference" "R1317"
			(at 9.4234 17.04467 0)
			(unlocked yes)
			(layer "F.SilkS")
			(effects
				(font
					(size 0.7874 0.5842)
					(thickness 0.1524)
				)
				(justify left)
			)
		)
		(property "Value" ""
			(at 0 0 0)
			(layer "F.Fab")
			(effects
				(font
					(size 1.27 1.27)
				)
			)
		)
		(duplicate_pad_numbers_are_jumpers no)
		(fp_line
			(start -0.7874 -0.4064)
			(end 0.7874 -0.4064)
			(stroke
				(width 0.1524)
				(type default)
			)
			(layer "F.SilkS")
		)
		(fp_line
			(start -0.7874 0.4064)
			(end -0.7874 -0.4064)
			(stroke
				(width 0.1524)
				(type default)
			)
			(layer "F.SilkS")
		)
		(fp_line
			(start 0.7874 -0.4064)
			(end 0.7874 0.4064)
			(stroke
				(width 0.1524)
				(type default)
			)
			(layer "F.SilkS")
		)
		(fp_line
			(start 0.7874 0.4064)
			(end -0.7874 0.4064)
			(stroke
				(width 0.1524)
				(type default)
			)
			(layer "F.SilkS")
		)
		(fp_poly
			(pts
				(xy -0.508 0.2794) (xy -0.508 0.2286) (xy -0.635 0.2286) (xy -0.635 -0.254) (xy -0.5334 -0.254)
				(xy -0.5334 -0.2794) (xy 0.5334 -0.2794) (xy 0.5334 -0.254) (xy 0.635 -0.254) (xy 0.635 0.254) (xy 0.5334 0.254)
				(xy 0.5334 0.2794)
			)
			(stroke
				(width 0)
				(type default)
			)
			(fill no)
			(layer "F.CrtYd")
		)
		(pad "1" smd rect
			(at 0.40005 0)
			(size 0.4572 0.508)
			(layers "F.Cu" "F.Mask" "F.Paste")
			(net "POWER_SW3_PWR_CTR_12V")
		)
		(pad "2" smd rect
			(at -0.40005 0)
			(size 0.4572 0.508)
			(layers "F.Cu" "F.Mask" "F.Paste")
			(net "POWER_SW3_PWR_CTR_12V_R")
		)
	)
	(footprint ""
		(layer "F.Cu")
		(at 137.593578 -59.688222 180)
		(property "Reference" "R512"
			(at 0.57785 -4.901184 0)
			(unlocked yes)
			(layer "F.SilkS")
			(effects
				(font
					(size 0.7874 0.5842)
					(thickness 0.1524)
				)
				(justify left)
			)
		)
		(property "Value" ""
			(at 0 0 180)
			(layer "F.Fab")
			(effects
				(font
					(size 1.27 1.27)
				)
			)
		)
		(duplicate_pad_numbers_are_jumpers no)
		(fp_line
			(start 0.7874 0.4064)
			(end -0.7874 0.4064)
			(stroke
				(width 0.1524)
				(type default)
			)
			(layer "F.SilkS")
		)
		(fp_line
			(start 0.7874 -0.4064)
			(end 0.7874 0.4064)
			(stroke
				(width 0.1524)
				(type default)
			)
			(layer "F.SilkS")
		)
		(fp_line
			(start -0.7874 0.4064)
			(end -0.7874 -0.4064)
			(stroke
				(width 0.1524)
				(type default)
			)
			(layer "F.SilkS")
		)
		(fp_line
			(start -0.7874 -0.4064)
			(end 0.7874 -0.4064)
			(stroke
				(width 0.1524)
				(type default)
			)
			(layer "F.SilkS")
		)
		(fp_poly
			(pts
				(xy -0.508 0.2794) (xy -0.508 0.2286) (xy -0.635 0.2286) (xy -0.635 -0.254) (xy -0.5334 -0.254)
				(xy -0.5334 -0.2794) (xy 0.5334 -0.2794) (xy 0.5334 -0.254) (xy 0.635 -0.254) (xy 0.635 0.254) (xy 0.5334 0.254)
				(xy 0.5334 0.2794)
			)
			(stroke
				(width 0)
				(type default)
			)
			(fill no)
			(layer "F.CrtYd")
		)
		(pad "1" smd rect
			(at 0.40005 0 180)
			(size 0.4572 0.508)
			(layers "F.Cu" "F.Mask" "F.Paste")
			(net "GND")
		)
		(pad "2" smd rect
			(at -0.40005 0 180)
			(size 0.4572 0.508)
			(layers "F.Cu" "F.Mask" "F.Paste")
			(net "SATA_NODE1_GPIO2")
		)
	)
	(footprint ""
		(layer "F.Cu")
		(at 112.067594 -164.305234)
		(property "Reference" "R681"
			(at -2.090674 -12.486894 0)
			(unlocked yes)
			(layer "F.SilkS")
			(effects
				(font
					(size 0.7874 0.5842)
					(thickness 0.1524)
				)
				(justify left)
			)
		)
		(property "Value" ""
			(at 0 0 0)
			(layer "F.Fab")
			(effects
				(font
					(size 1.27 1.27)
				)
			)
		)
		(duplicate_pad_numbers_are_jumpers no)
		(fp_line
			(start -0.7874 -0.4064)
			(end 0.7874 -0.4064)
			(stroke
				(width 0.1524)
				(type default)
			)
			(layer "F.SilkS")
		)
		(fp_line
			(start -0.7874 0.4064)
			(end -0.7874 -0.4064)
			(stroke
				(width 0.1524)
				(type default)
			)
			(layer "F.SilkS")
		)
		(fp_line
			(start 0.7874 -0.4064)
			(end 0.7874 0.4064)
			(stroke
				(width 0.1524)
				(type default)
			)
			(layer "F.SilkS")
		)
		(fp_line
			(start 0.7874 0.4064)
			(end -0.7874 0.4064)
			(stroke
				(width 0.1524)
				(type default)
			)
			(layer "F.SilkS")
		)
		(fp_poly
			(pts
				(xy -0.508 0.2794) (xy -0.508 0.2286) (xy -0.635 0.2286) (xy -0.635 -0.254) (xy -0.5334 -0.254)
				(xy -0.5334 -0.2794) (xy 0.5334 -0.2794) (xy 0.5334 -0.254) (xy 0.635 -0.254) (xy 0.635 0.254) (xy 0.5334 0.254)
				(xy 0.5334 0.2794)
			)
			(stroke
				(width 0)
				(type default)
			)
			(fill no)
			(layer "F.CrtYd")
		)
		(pad "1" smd rect
			(at 0.40005 0)
			(size 0.4572 0.508)
			(layers "F.Cu" "F.Mask" "F.Paste")
			(net "I2C_COM3_SDA")
		)
		(pad "2" smd rect
			(at -0.40005 0)
			(size 0.4572 0.508)
			(layers "F.Cu" "F.Mask" "F.Paste")
			(net "I2C_PDB_SDA")
		)
	)
	(footprint ""
		(layer "F.Cu")
		(at 104.605836 -138.90117 -90)
		(property "Reference" "PC115"
			(at -3.936238 3.473196 0)
			(unlocked yes)
			(layer "F.SilkS")
			(effects
				(font
					(size 0.635 0.4064)
					(thickness 0.1524)
				)
				(justify left)
			)
		)
		(property "Value" ""
			(at 0 0 270)
			(layer "F.Fab")
			(effects
				(font
					(size 1.27 1.27)
				)
			)
		)
		(duplicate_pad_numbers_are_jumpers no)
		(fp_line
			(start -0.7874 0.4064)
			(end -0.7874 -0.4064)
			(stroke
				(width 0.1524)
				(type default)
			)
			(layer "F.SilkS")
		)
		(fp_line
			(start 0.7874 0.4064)
			(end -0.7874 0.4064)
			(stroke
				(width 0.1524)
				(type default)
			)
			(layer "F.SilkS")
		)
		(fp_line
			(start 0 0.381)
			(end 0 -0.381)
			(stroke
				(width 0.1524)
				(type default)
			)
			(layer "F.SilkS")
		)
		(fp_line
			(start -0.7874 -0.4064)
			(end 0.7874 -0.4064)
			(stroke
				(width 0.1524)
				(type default)
			)
			(layer "F.SilkS")
		)
		(fp_line
			(start 0.7874 -0.4064)
			(end 0.7874 0.4064)
			(stroke
				(width 0.1524)
				(type default)
			)
			(layer "F.SilkS")
		)
		(fp_poly
			(pts
				(xy -0.5334 0.254) (xy -0.635 0.254) (xy -0.635 0.2286) (xy -0.635 -0.254) (xy -0.5334 -0.254) (xy -0.5334 -0.2794)
				(xy 0.5334 -0.2794) (xy 0.5334 -0.254) (xy 0.635 -0.254) (xy 0.635 0.254) (xy 0.5334 0.254) (xy 0.5334 0.2794)
				(xy -0.508 0.2794) (xy -0.5334 0.2794)
			)
			(stroke
				(width 0)
				(type default)
			)
			(fill no)
			(layer "F.CrtYd")
		)
		(pad "1" smd rect
			(at 0.40005 0 270)
			(size 0.4572 0.508)
			(layers "F.Cu" "F.Mask" "F.Paste")
			(net "VR_PVCCP_NODE1_IBIAS")
		)
		(pad "2" smd rect
			(at -0.40005 0 270)
			(size 0.4572 0.508)
			(layers "F.Cu" "F.Mask" "F.Paste")
			(net "AGND_PVCCP_NODE1")
		)
	)
)
